(kicad_pcb
	(version 20260206)
	(generator "pcbnew")
	(generator_version "10.0")
	(general
		(thickness 1.6)
		(legacy_teardrops no)
	)
	(paper "A4")
	(title_block
		(title "03242023_DA0F0TMBIJ0_F0T_Motherboard_J_brd_V01_OCP.brd")
		(comment 1 "Grand Teton / footprints 3439-3445 of 6105")
	)
	(layers
		(0 "F.Cu" signal "TOP")
		(4 "In1.Cu" signal "GND")
		(6 "In2.Cu" signal "IN1")
		(8 "In3.Cu" signal "GND1")
		(10 "In4.Cu" signal "IN2")
		(12 "In5.Cu" signal "GND2")
		(14 "In6.Cu" signal "IN3")
		(16 "In7.Cu" signal "GND3")
		(18 "In8.Cu" signal "VCC")
		(20 "In9.Cu" signal "VCC1")
		(22 "In10.Cu" signal "GND4")
		(24 "In11.Cu" signal "IN4")
		(26 "In12.Cu" signal "GND5")
		(28 "In13.Cu" signal "IN5")
		(30 "In14.Cu" signal "GND6")
		(32 "In15.Cu" signal "IN6")
		(34 "In16.Cu" signal "GND7")
		(2 "B.Cu" signal "BOTTOM")
		(9 "F.Adhes" user "F.Adhesive")
		(11 "B.Adhes" user "B.Adhesive")
		(13 "F.Paste" user "Package Geometry/Pastemask Top")
		(15 "B.Paste" user "Package Geometry/Pastemask Bottom")
		(5 "F.SilkS" user "Ref Des/Silkscreen Top")
		(7 "B.SilkS" user "Ref Des/Silkscreen Bottom")
		(1 "F.Mask" user "Board Geometry/Soldermask Top")
		(3 "B.Mask" user "Board Geometry/Soldermask Bottom")
		(17 "Dwgs.User" user "User.Drawings")
		(19 "Cmts.User" user "User.Comments")
		(21 "Eco1.User" user "User.Eco1")
		(23 "Eco2.User" user "User.Eco2")
		(25 "Edge.Cuts" user "Board Geometry/Outline")
		(27 "Margin" user)
		(31 "F.CrtYd" user "Package Geometry/Place Bound Top")
		(29 "B.CrtYd" user "Package Geometry/Place Bound Bottom")
		(35 "F.Fab" user "Ref Des/Assembly Top")
		(33 "B.Fab" user "Ref Des/Assembly Bottom")
	)
	(footprint ""
		(layer "F.Cu")
		(at 369.129818 -387.779006 180)
		(property "Reference" "R4164"
			(at 0 0 180)
			(layer "F.SilkS")
			(hide yes)
			(effects
				(font
					(size 1.27 1.27)
				)
			)
		)
		(property "Value" ""
			(at 0 0 180)
			(layer "F.Fab")
			(effects
				(font
					(size 1.27 1.27)
				)
			)
		)
		(duplicate_pad_numbers_are_jumpers no)
		(fp_line
			(start 0.7874 0.4064)
			(end -0.7874 0.4064)
			(stroke
				(width 0.1524)
				(type default)
			)
			(layer "F.SilkS")
		)
		(fp_line
			(start 0.7874 -0.4064)
			(end 0.7874 0.4064)
			(stroke
				(width 0.1524)
				(type default)
			)
			(layer "F.SilkS")
		)
		(fp_line
			(start -0.7874 0.4064)
			(end -0.7874 -0.4064)
			(stroke
				(width 0.1524)
				(type default)
			)
			(layer "F.SilkS")
		)
		(fp_line
			(start -0.7874 -0.4064)
			(end 0.7874 -0.4064)
			(stroke
				(width 0.1524)
				(type default)
			)
			(layer "F.SilkS")
		)
		(fp_line
			(start 0.67945 0.3048)
			(end 0.120396 0.3048)
			(stroke
				(width 0.1)
				(type default)
			)
			(layer "F.Fab")
		)
		(fp_line
			(start 0.67945 -0.3048)
			(end 0.67945 0.3048)
			(stroke
				(width 0.1)
				(type default)
			)
			(layer "F.Fab")
		)
		(fp_line
			(start 0.12065 -0.2794)
			(end 0.12065 -0.3048)
			(stroke
				(width 0.1)
				(type default)
			)
			(layer "F.Fab")
		)
		(fp_line
			(start 0.12065 -0.3048)
			(end 0.67945 -0.3048)
			(stroke
				(width 0.1)
				(type default)
			)
			(layer "F.Fab")
		)
		(fp_line
			(start 0.120396 0.3048)
			(end 0.120396 0.2794)
			(stroke
				(width 0.1)
				(type default)
			)
			(layer "F.Fab")
		)
		(fp_line
			(start 0.120396 0.2794)
			(end -0.12065 0.2794)
			(stroke
				(width 0.1)
				(type default)
			)
			(layer "F.Fab")
		)
		(fp_line
			(start -0.12065 0.3048)
			(end -0.67945 0.3048)
			(stroke
				(width 0.1)
				(type default)
			)
			(layer "F.Fab")
		)
		(fp_line
			(start -0.12065 0.2794)
			(end -0.12065 0.3048)
			(stroke
				(width 0.1)
				(type default)
			)
			(layer "F.Fab")
		)
		(fp_line
			(start -0.12065 -0.2794)
			(end 0.12065 -0.2794)
			(stroke
				(width 0.1)
				(type default)
			)
			(layer "F.Fab")
		)
		(fp_line
			(start -0.12065 -0.305054)
			(end -0.12065 -0.2794)
			(stroke
				(width 0.1)
				(type default)
			)
			(layer "F.Fab")
		)
		(fp_line
			(start -0.67945 0.3048)
			(end -0.67945 -0.305054)
			(stroke
				(width 0.1)
				(type default)
			)
			(layer "F.Fab")
		)
		(fp_line
			(start -0.67945 -0.305054)
			(end -0.12065 -0.305054)
			(stroke
				(width 0.1)
				(type default)
			)
			(layer "F.Fab")
		)
		(pad "1" smd circle
			(at -0.40005 0 180)
			(size 0 0)
			(layers "F.Cu" "F.Mask" "F.Paste")
			(net "P3V3_AUX")
		)
		(pad "2" smd circle
			(at 0.40005 0 180)
			(size 0 0)
			(layers "F.Cu" "F.Mask" "F.Paste")
			(net "GPU_3V3IO_RSVD1_N")
		)
	)
	(footprint ""
		(layer "F.Cu")
		(at 67.680078 -408.517344 -90)
		(property "Reference" "C696"
			(at 0 0 270)
			(layer "F.SilkS")
			(hide yes)
			(effects
				(font
					(size 1.27 1.27)
				)
			)
		)
		(property "Value" ""
			(at 0 0 270)
			(layer "F.Fab")
			(effects
				(font
					(size 1.27 1.27)
				)
			)
		)
		(duplicate_pad_numbers_are_jumpers no)
		(fp_line
			(start -0.299974 0.150114)
			(end -0.299974 -0.150114)
			(stroke
				(width 0.1)
				(type default)
			)
			(layer "F.Fab")
		)
		(fp_line
			(start 0.299974 0.150114)
			(end -0.299974 0.150114)
			(stroke
				(width 0.1)
				(type default)
			)
			(layer "F.Fab")
		)
		(fp_line
			(start -0.299974 -0.150114)
			(end 0.299974 -0.150114)
			(stroke
				(width 0.1)
				(type default)
			)
			(layer "F.Fab")
		)
		(fp_line
			(start 0.299974 -0.150114)
			(end 0.299974 0.150114)
			(stroke
				(width 0.1)
				(type default)
			)
			(layer "F.Fab")
		)
		(pad "1" smd rect
			(at -0.2667 0 270)
			(size 0.3048 0.381)
			(layers "F.Cu" "F.Mask" "F.Paste")
			(net "P5E_CPU1_PE4_TX_C_DN<6>")
		)
		(pad "2" smd rect
			(at 0.2667 0 270)
			(size 0.3048 0.381)
			(layers "F.Cu" "F.Mask" "F.Paste")
			(net "P5E_CPU1_PE4_TX_DN<6>")
		)
	)
	(footprint ""
		(layer "F.Cu")
		(at 185.230008 -408.912822 180)
		(property "Reference" "PR3926"
			(at 0 0 180)
			(layer "F.SilkS")
			(hide yes)
			(effects
				(font
					(size 1.27 1.27)
				)
			)
		)
		(property "Value" ""
			(at 0 0 180)
			(layer "F.Fab")
			(effects
				(font
					(size 1.27 1.27)
				)
			)
		)
		(duplicate_pad_numbers_are_jumpers no)
		(fp_line
			(start 0.7874 0.4064)
			(end -0.7874 0.4064)
			(stroke
				(width 0.1524)
				(type default)
			)
			(layer "F.SilkS")
		)
		(fp_line
			(start 0.7874 -0.4064)
			(end 0.7874 0.4064)
			(stroke
				(width 0.1524)
				(type default)
			)
			(layer "F.SilkS")
		)
		(fp_line
			(start -0.7874 0.4064)
			(end -0.7874 -0.4064)
			(stroke
				(width 0.1524)
				(type default)
			)
			(layer "F.SilkS")
		)
		(fp_line
			(start -0.7874 -0.4064)
			(end 0.7874 -0.4064)
			(stroke
				(width 0.1524)
				(type default)
			)
			(layer "F.SilkS")
		)
		(fp_line
			(start 0.67945 0.3048)
			(end 0.120396 0.3048)
			(stroke
				(width 0.1)
				(type default)
			)
			(layer "F.Fab")
		)
		(fp_line
			(start 0.67945 -0.3048)
			(end 0.67945 0.3048)
			(stroke
				(width 0.1)
				(type default)
			)
			(layer "F.Fab")
		)
		(fp_line
			(start 0.12065 -0.2794)
			(end 0.12065 -0.3048)
			(stroke
				(width 0.1)
				(type default)
			)
			(layer "F.Fab")
		)
		(fp_line
			(start 0.12065 -0.3048)
			(end 0.67945 -0.3048)
			(stroke
				(width 0.1)
				(type default)
			)
			(layer "F.Fab")
		)
		(fp_line
			(start 0.120396 0.3048)
			(end 0.120396 0.2794)
			(stroke
				(width 0.1)
				(type default)
			)
			(layer "F.Fab")
		)
		(fp_line
			(start 0.120396 0.2794)
			(end -0.12065 0.2794)
			(stroke
				(width 0.1)
				(type default)
			)
			(layer "F.Fab")
		)
		(fp_line
			(start -0.12065 0.3048)
			(end -0.67945 0.3048)
			(stroke
				(width 0.1)
				(type default)
			)
			(layer "F.Fab")
		)
		(fp_line
			(start -0.12065 0.2794)
			(end -0.12065 0.3048)
			(stroke
				(width 0.1)
				(type default)
			)
			(layer "F.Fab")
		)
		(fp_line
			(start -0.12065 -0.2794)
			(end 0.12065 -0.2794)
			(stroke
				(width 0.1)
				(type default)
			)
			(layer "F.Fab")
		)
		(fp_line
			(start -0.12065 -0.305054)
			(end -0.12065 -0.2794)
			(stroke
				(width 0.1)
				(type default)
			)
			(layer "F.Fab")
		)
		(fp_line
			(start -0.67945 0.3048)
			(end -0.67945 -0.305054)
			(stroke
				(width 0.1)
				(type default)
			)
			(layer "F.Fab")
		)
		(fp_line
			(start -0.67945 -0.305054)
			(end -0.12065 -0.305054)
			(stroke
				(width 0.1)
				(type default)
			)
			(layer "F.Fab")
		)
		(pad "1" smd circle
			(at -0.40005 0 180)
			(size 0 0)
			(layers "F.Cu" "F.Mask" "F.Paste")
			(net "P12V_PSU")
		)
		(pad "2" smd circle
			(at 0.40005 0 180)
			(size 0 0)
			(layers "F.Cu" "F.Mask" "F.Paste")
			(net "HSC_VSENSE")
		)
	)
	(footprint ""
		(layer "F.Cu")
		(at 125.264926 -119.810784 -90)
		(property "Reference" "R861"
			(at 0 0 270)
			(layer "F.SilkS")
			(hide yes)
			(effects
				(font
					(size 1.27 1.27)
				)
			)
		)
		(property "Value" ""
			(at 0 0 270)
			(layer "F.Fab")
			(effects
				(font
					(size 1.27 1.27)
				)
			)
		)
		(duplicate_pad_numbers_are_jumpers no)
		(fp_line
			(start -0.7874 0.4064)
			(end -0.7874 -0.4064)
			(stroke
				(width 0.1524)
				(type default)
			)
			(layer "F.SilkS")
		)
		(fp_line
			(start 0.7874 0.4064)
			(end -0.7874 0.4064)
			(stroke
				(width 0.1524)
				(type default)
			)
			(layer "F.SilkS")
		)
		(fp_line
			(start -0.7874 -0.4064)
			(end 0.7874 -0.4064)
			(stroke
				(width 0.1524)
				(type default)
			)
			(layer "F.SilkS")
		)
		(fp_line
			(start 0.7874 -0.4064)
			(end 0.7874 0.4064)
			(stroke
				(width 0.1524)
				(type default)
			)
			(layer "F.SilkS")
		)
		(fp_line
			(start -0.67945 0.3048)
			(end -0.67945 -0.305054)
			(stroke
				(width 0.1)
				(type default)
			)
			(layer "F.Fab")
		)
		(fp_line
			(start -0.12065 0.3048)
			(end -0.67945 0.3048)
			(stroke
				(width 0.1)
				(type default)
			)
			(layer "F.Fab")
		)
		(fp_line
			(start 0.120396 0.3048)
			(end 0.120396 0.2794)
			(stroke
				(width 0.1)
				(type default)
			)
			(layer "F.Fab")
		)
		(fp_line
			(start 0.67945 0.3048)
			(end 0.120396 0.3048)
			(stroke
				(width 0.1)
				(type default)
			)
			(layer "F.Fab")
		)
		(fp_line
			(start -0.12065 0.2794)
			(end -0.12065 0.3048)
			(stroke
				(width 0.1)
				(type default)
			)
			(layer "F.Fab")
		)
		(fp_line
			(start 0.120396 0.2794)
			(end -0.12065 0.2794)
			(stroke
				(width 0.1)
				(type default)
			)
			(layer "F.Fab")
		)
		(fp_line
			(start -0.12065 -0.2794)
			(end 0.12065 -0.2794)
			(stroke
				(width 0.1)
				(type default)
			)
			(layer "F.Fab")
		)
		(fp_line
			(start 0.12065 -0.2794)
			(end 0.12065 -0.3048)
			(stroke
				(width 0.1)
				(type default)
			)
			(layer "F.Fab")
		)
		(fp_line
			(start 0.12065 -0.3048)
			(end 0.67945 -0.3048)
			(stroke
				(width 0.1)
				(type default)
			)
			(layer "F.Fab")
		)
		(fp_line
			(start 0.67945 -0.3048)
			(end 0.67945 0.3048)
			(stroke
				(width 0.1)
				(type default)
			)
			(layer "F.Fab")
		)
		(fp_line
			(start -0.67945 -0.305054)
			(end -0.12065 -0.305054)
			(stroke
				(width 0.1)
				(type default)
			)
			(layer "F.Fab")
		)
		(fp_line
			(start -0.12065 -0.305054)
			(end -0.12065 -0.2794)
			(stroke
				(width 0.1)
				(type default)
			)
			(layer "F.Fab")
		)
		(pad "1" smd circle
			(at -0.40005 0 270)
			(size 0 0)
			(layers "F.Cu" "F.Mask" "F.Paste")
			(net "RST_CPU1_DRAM_EF_N")
		)
		(pad "2" smd circle
			(at 0.40005 0 270)
			(size 0 0)
			(layers "F.Cu" "F.Mask" "F.Paste")
			(net "RST_CPU1_DRAM_EF_PLD_N")
		)
	)
	(footprint ""
		(layer "F.Cu")
		(at 292.61054 -93.482414 180)
		(property "Reference" "R1331"
			(at 0 0 180)
			(layer "F.SilkS")
			(hide yes)
			(effects
				(font
					(size 1.27 1.27)
				)
			)
		)
		(property "Value" ""
			(at 0 0 180)
			(layer "F.Fab")
			(effects
				(font
					(size 1.27 1.27)
				)
			)
		)
		(duplicate_pad_numbers_are_jumpers no)
		(fp_line
			(start 0.7874 0.4064)
			(end -0.7874 0.4064)
			(stroke
				(width 0.1524)
				(type default)
			)
			(layer "F.SilkS")
		)
		(fp_line
			(start 0.7874 -0.4064)
			(end 0.7874 0.4064)
			(stroke
				(width 0.1524)
				(type default)
			)
			(layer "F.SilkS")
		)
		(fp_line
			(start -0.7874 0.4064)
			(end -0.7874 -0.4064)
			(stroke
				(width 0.1524)
				(type default)
			)
			(layer "F.SilkS")
		)
		(fp_line
			(start -0.7874 -0.4064)
			(end 0.7874 -0.4064)
			(stroke
				(width 0.1524)
				(type default)
			)
			(layer "F.SilkS")
		)
		(fp_line
			(start 0.67945 0.3048)
			(end 0.120396 0.3048)
			(stroke
				(width 0.1)
				(type default)
			)
			(layer "F.Fab")
		)
		(fp_line
			(start 0.67945 -0.3048)
			(end 0.67945 0.3048)
			(stroke
				(width 0.1)
				(type default)
			)
			(layer "F.Fab")
		)
		(fp_line
			(start 0.12065 -0.2794)
			(end 0.12065 -0.3048)
			(stroke
				(width 0.1)
				(type default)
			)
			(layer "F.Fab")
		)
		(fp_line
			(start 0.12065 -0.3048)
			(end 0.67945 -0.3048)
			(stroke
				(width 0.1)
				(type default)
			)
			(layer "F.Fab")
		)
		(fp_line
			(start 0.120396 0.3048)
			(end 0.120396 0.2794)
			(stroke
				(width 0.1)
				(type default)
			)
			(layer "F.Fab")
		)
		(fp_line
			(start 0.120396 0.2794)
			(end -0.12065 0.2794)
			(stroke
				(width 0.1)
				(type default)
			)
			(layer "F.Fab")
		)
		(fp_line
			(start -0.12065 0.3048)
			(end -0.67945 0.3048)
			(stroke
				(width 0.1)
				(type default)
			)
			(layer "F.Fab")
		)
		(fp_line
			(start -0.12065 0.2794)
			(end -0.12065 0.3048)
			(stroke
				(width 0.1)
				(type default)
			)
			(layer "F.Fab")
		)
		(fp_line
			(start -0.12065 -0.2794)
			(end 0.12065 -0.2794)
			(stroke
				(width 0.1)
				(type default)
			)
			(layer "F.Fab")
		)
		(fp_line
			(start -0.12065 -0.305054)
			(end -0.12065 -0.2794)
			(stroke
				(width 0.1)
				(type default)
			)
			(layer "F.Fab")
		)
		(fp_line
			(start -0.67945 0.3048)
			(end -0.67945 -0.305054)
			(stroke
				(width 0.1)
				(type default)
			)
			(layer "F.Fab")
		)
		(fp_line
			(start -0.67945 -0.305054)
			(end -0.12065 -0.305054)
			(stroke
				(width 0.1)
				(type default)
			)
			(layer "F.Fab")
		)
		(pad "1" smd circle
			(at -0.40005 0 180)
			(size 0 0)
			(layers "F.Cu" "F.Mask" "F.Paste")
			(net "P3V3_AUX")
		)
		(pad "2" smd circle
			(at 0.40005 0 180)
			(size 0 0)
			(layers "F.Cu" "F.Mask" "F.Paste")
			(net "SMB_FRU_3V3AUX_SCL")
		)
	)
	(footprint ""
		(layer "F.Cu")
		(at 304.034952 -54.012592 180)
		(property "Reference" "R1341"
			(at 0 0 180)
			(layer "F.SilkS")
			(hide yes)
			(effects
				(font
					(size 1.27 1.27)
				)
			)
		)
		(property "Value" ""
			(at 0 0 180)
			(layer "F.Fab")
			(effects
				(font
					(size 1.27 1.27)
				)
			)
		)
		(duplicate_pad_numbers_are_jumpers no)
		(fp_line
			(start 0.7874 0.4064)
			(end -0.7874 0.4064)
			(stroke
				(width 0.1524)
				(type default)
			)
			(layer "F.SilkS")
		)
		(fp_line
			(start 0.7874 -0.4064)
			(end 0.7874 0.4064)
			(stroke
				(width 0.1524)
				(type default)
			)
			(layer "F.SilkS")
		)
		(fp_line
			(start -0.7874 0.4064)
			(end -0.7874 -0.4064)
			(stroke
				(width 0.1524)
				(type default)
			)
			(layer "F.SilkS")
		)
		(fp_line
			(start -0.7874 -0.4064)
			(end 0.7874 -0.4064)
			(stroke
				(width 0.1524)
				(type default)
			)
			(layer "F.SilkS")
		)
		(fp_line
			(start 0.67945 0.3048)
			(end 0.120396 0.3048)
			(stroke
				(width 0.1)
				(type default)
			)
			(layer "F.Fab")
		)
		(fp_line
			(start 0.67945 -0.3048)
			(end 0.67945 0.3048)
			(stroke
				(width 0.1)
				(type default)
			)
			(layer "F.Fab")
		)
		(fp_line
			(start 0.12065 -0.2794)
			(end 0.12065 -0.3048)
			(stroke
				(width 0.1)
				(type default)
			)
			(layer "F.Fab")
		)
		(fp_line
			(start 0.12065 -0.3048)
			(end 0.67945 -0.3048)
			(stroke
				(width 0.1)
				(type default)
			)
			(layer "F.Fab")
		)
		(fp_line
			(start 0.120396 0.3048)
			(end 0.120396 0.2794)
			(stroke
				(width 0.1)
				(type default)
			)
			(layer "F.Fab")
		)
		(fp_line
			(start 0.120396 0.2794)
			(end -0.12065 0.2794)
			(stroke
				(width 0.1)
				(type default)
			)
			(layer "F.Fab")
		)
		(fp_line
			(start -0.12065 0.3048)
			(end -0.67945 0.3048)
			(stroke
				(width 0.1)
				(type default)
			)
			(layer "F.Fab")
		)
		(fp_line
			(start -0.12065 0.2794)
			(end -0.12065 0.3048)
			(stroke
				(width 0.1)
				(type default)
			)
			(layer "F.Fab")
		)
		(fp_line
			(start -0.12065 -0.2794)
			(end 0.12065 -0.2794)
			(stroke
				(width 0.1)
				(type default)
			)
			(layer "F.Fab")
		)
		(fp_line
			(start -0.12065 -0.305054)
			(end -0.12065 -0.2794)
			(stroke
				(width 0.1)
				(type default)
			)
			(layer "F.Fab")
		)
		(fp_line
			(start -0.67945 0.3048)
			(end -0.67945 -0.305054)
			(stroke
				(width 0.1)
				(type default)
			)
			(layer "F.Fab")
		)
		(fp_line
			(start -0.67945 -0.305054)
			(end -0.12065 -0.305054)
			(stroke
				(width 0.1)
				(type default)
			)
			(layer "F.Fab")
		)
		(pad "1" smd circle
			(at -0.40005 0 180)
			(size 0 0)
			(layers "F.Cu" "F.Mask" "F.Paste")
			(net "FM_ADR_COMPLETE")
		)
		(pad "2" smd circle
			(at 0.40005 0 180)
			(size 0 0)
			(layers "F.Cu" "F.Mask" "F.Paste")
			(net "GND")
		)
	)
	(footprint ""
		(layer "F.Cu")
		(at 330.848716 -13.985748)
		(property "Reference" "U154"
			(at 3.25374 0.200152 0)
			(unlocked yes)
			(layer "F.SilkS")
			(effects
				(font
					(size 0.7874 0.5842)
					(thickness 0.1524)
				)
				(justify left)
			)
		)
		(property "Value" ""
			(at 0 0 0)
			(layer "F.Fab")
			(effects
				(font
					(size 1.27 1.27)
				)
			)
		)
		(duplicate_pad_numbers_are_jumpers no)
		(fp_line
			(start -1.400048 1.100074)
			(end -1.400048 -1.100074)
			(stroke
				(width 0.1524)
				(type default)
			)
			(layer "F.SilkS")
		)
		(fp_line
			(start 1.400048 -1.100074)
			(end -1.400048 -1.100074)
			(stroke
				(width 0.1524)
				(type default)
			)
			(layer "F.SilkS")
		)
		(fp_line
			(start 1.400048 -1.100074)
			(end 1.400048 1.100074)
			(stroke
				(width 0.1524)
				(type default)
			)
			(layer "F.SilkS")
		)
		(fp_line
			(start 1.400048 1.100074)
			(end -1.400048 1.100074)
			(stroke
				(width 0.1524)
				(type default)
			)
			(layer "F.SilkS")
		)
		(fp_poly
			(pts
				(xy -0.812292 -1.192276) (xy -0.534416 -2.02565) (xy 0.021082 -1.470152)
			)
			(stroke
				(width 0)
				(type default)
			)
			(fill yes)
			(layer "F.SilkS")
		)
		(fp_line
			(start -0.674878 -1.100074)
			(end 0.674878 -1.100074)
			(stroke
				(width 0.1)
				(type default)
			)
			(layer "F.Fab")
		)
		(fp_line
			(start -0.674878 1.100074)
			(end -0.674878 -1.100074)
			(stroke
				(width 0.1)
				(type default)
			)
			(layer "F.Fab")
		)
		(fp_line
			(start 0.674878 -1.100074)
			(end 0.674878 1.100074)
			(stroke
				(width 0.1)
				(type default)
			)
			(layer "F.Fab")
		)
		(fp_line
			(start 0.674878 1.100074)
			(end -0.674878 1.100074)
			(stroke
				(width 0.1)
				(type default)
			)
			(layer "F.Fab")
		)
		(fp_poly
			(pts
				(xy -1.590548 -0.649986) (xy -2.606548 -1.157986) (xy -2.606548 -0.141986)
			)
			(stroke
				(width 0)
				(type default)
			)
			(fill yes)
			(layer "F.Fab")
		)
		(pad "1" smd rect
			(at -0.94996 -0.649986 270)
			(size 0.4318 0.6096)
			(layers "F.Cu" "F.Mask" "F.Paste")
			(net "NC_ESPI_PLD_R_EN_BUF")
		)
		(pad "2" smd rect
			(at -0.94996 0 270)
			(size 0.4318 0.6096)
			(layers "F.Cu" "F.Mask" "F.Paste")
			(net "FM_ESPI_PLD_R1_EN")
		)
		(pad "3" smd rect
			(at -0.94996 0.649986 270)
			(size 0.4318 0.6096)
			(layers "F.Cu" "F.Mask" "F.Paste")
			(net "GND")
		)
		(pad "4" smd rect
			(at 0.94996 0.649986 270)
			(size 0.4318 0.6096)
			(layers "F.Cu" "F.Mask" "F.Paste")
			(net "FM_ESPI_PLD_R_EN_BUF")
		)
		(pad "5" smd rect
			(at 0.94996 -0.649986 270)
			(size 0.4318 0.6096)
			(layers "F.Cu" "F.Mask" "F.Paste")
			(net "P3V3_AUX")
		)
	)
)
